FILE_TYPE = CONNECTIVITY;
{Allegro Design Entry HDL 17.2-2016 S081 (4005846) 1/11/2022}
"PAGE_NUMBER" = 12;
0"NC";
END.
